# T6G (Grand Teton) — schematic netlist excerpt (pin names and nets, part order shuffled) for the footprints in the layout excerpt that follows; sources: Cadence DE-HDL packaged netlist, KiCad conversion of 04192023_DAF0TMB3IC0_F0TG_MB_C_brd_V02_OCP.brd

J1  SCONN288_DDR506112002KQ  IO  pkg DDR288S_1-1VXC  page 86
  VIN_BULK0  = P12V_MEM_CPU0
  RFU0  = NC
  VIN_MGMT  = P3V3_AUX
  HSCL  = I3C_SPD_DDRA_CPU0_SCL
  HSDA  = I3C_SPD_DDRA_CPU0_SDA
  VSS0  = GND
  DQ0_A  = M_A_CPU0_SA_DQ<0>
  VSS1  = GND
  DQ1_A  = M_A_CPU0_SA_DQ<1>
  VSS2  = GND
  DQS0_A_T  = M_A_CPU0_SA_DQS_DP<0>
  DQS0_A_C  = M_A_CPU0_SA_DQS_DN<0>
  VSS3  = GND
  DQ4_A  = M_A_CPU0_SA_DQ<4>
  VSS4  = GND
  DQ5_A  = M_A_CPU0_SA_DQ<5>
  VSS5  = GND
  DQ8_A  = M_A_CPU0_SA_DQ<8>
  VSS6  = GND
  DQ9_A  = M_A_CPU0_SA_DQ<9>
  VSS7  = GND
  DQS1_A_T  = M_A_CPU0_SA_DQS_DP<1>
  DQS1_A_C  = M_A_CPU0_SA_DQS_DN<1>
  VSS8  = GND
  DQ12_A  = M_A_CPU0_SA_DQ<12>
  VSS9  = GND
  DQ13_A  = M_A_CPU0_SA_DQ<13>
  VSS10  = GND
  DQ16_A  = M_A_CPU0_SA_DQ<16>
  VSS11  = GND
  DQ17_A  = M_A_CPU0_SA_DQ<17>
  VSS12  = GND
  DQS2_A_T  = M_A_CPU0_SA_DQS_DP<2>
  DQS2_A_C  = M_A_CPU0_SA_DQS_DN<2>
  VSS13  = GND
  DQ20_A  = M_A_CPU0_SA_DQ<20>
  VSS14  = GND
  DQ21_A  = M_A_CPU0_SA_DQ<21>
  VSS15  = GND
  DQ24_A  = M_A_CPU0_SA_DQ<24>
  VSS16  = GND
  DQ25_A  = M_A_CPU0_SA_DQ<25>
  VSS17  = GND
  DQS3_A_T  = M_A_CPU0_SA_DQS_DP<3>
  DQS3_A_C  = M_A_CPU0_SA_DQS_DN<3>
  VSS18  = GND
  DQ28_A  = M_A_CPU0_SA_DQ<28>
  VSS19  = GND
  DQ29_A  = M_A_CPU0_SA_DQ<29>
  VSS20  = GND
  CB0_A  = M_A_CPU0_SA_CB<0>
  VSS21  = GND
  CB1_A  = M_A_CPU0_SA_CB<1>
  VSS22  = GND
  DQS4_A_T  = M_A_CPU0_SA_DQS_DP<4>
  DQS4_A_C  = M_A_CPU0_SA_DQS_DN<4>
  VSS23  = GND
  CB4_A  = M_A_CPU0_SA_CB<4>
  VSS24  = GND
  CB5_A  = M_A_CPU0_SA_CB<5>
  VSS25  = GND
  ALERT_N  = M_A_CPU0_ALERT_N
  VSS26  = GND
  CS0_A_N  = M_A_CPU0_SA_CS_N<0>
  VSS27  = GND
  CA0_A  = M_A_CPU0_SA_CA<0>
  VSS28  = GND
  CA2_A  = M_A_CPU0_SA_CA<2>
  VSS29  = GND
  CA4_A  = M_A_CPU0_SA_CA<4>
  VSS30  = GND
  CA6_A  = M_A_CPU0_SA_CA<6>
  VSS31  = GND
  PAR_A  = M_A_CPU0_SA_PAR
  VSS32  = GND
  CA0_B  = M_A_CPU0_SB_CA<0>
  VSS33  = GND
  CA2_B  = M_A_CPU0_SB_CA<2>
  VSS34  = GND
  CA4_B  = M_A_CPU0_SB_CA<4>
  VSS35  = GND
  CA6_B  = M_A_CPU0_SB_CA<6>
  VSS36  = GND
  CS0_B_N  = M_A_CPU0_SB_CS_N<0>
  VSS37  = GND
  \lbd||rsp_a_n\  = M_A_CPU0_SA_RSP<0>
  \lbs||rsp_b_n\  = M_A_CPU0_SB_RSP<0>
  VSS38  = GND
  CB4_B  = M_A_CPU0_SB_CB<4>
  VSS39  = GND
  CB5_B  = M_A_CPU0_SB_CB<5>
  VSS40  = GND
  \dqs9_b_t||tdqs9_b_t||dbi4_b_n\  = M_A_CPU0_SB_DQS_DP<9>
  \dqs9_b_c||tdqs9_b_c\  = M_A_CPU0_SB_DQS_DN<9>
  VSS41  = GND
  CB0_B  = M_A_CPU0_SB_CB<0>
  VSS42  = GND
  CB1_B  = M_A_CPU0_SB_CB<1>
  VSS43  = GND
  DQ0_B  = M_A_CPU0_SB_DQ<0>
  VSS44  = GND
  DQ1_B  = M_A_CPU0_SB_DQ<1>
  VSS45  = GND
  DQS0_B_T  = M_A_CPU0_SB_DQS_DP<0>
  DQS0_B_C  = M_A_CPU0_SB_DQS_DN<0>
  VSS46  = GND
  DQ4_B  = M_A_CPU0_SB_DQ<4>
  VSS47  = GND
  DQ5_B  = M_A_CPU0_SB_DQ<5>
  VSS48  = GND
  DQ8_B  = M_A_CPU0_SB_DQ<8>
  VSS49  = GND
  DQ9_B  = M_A_CPU0_SB_DQ<9>
  VSS50  = GND
  DQS1_B_T  = M_A_CPU0_SB_DQS_DP<1>
  DQS1_B_C  = M_A_CPU0_SB_DQS_DN<1>
  VSS51  = GND
  DQ12_B  = M_A_CPU0_SB_DQ<12>
  VSS52  = GND
  DQ13_B  = M_A_CPU0_SB_DQ<13>
  VSS53  = GND
  DQ16_B  = M_A_CPU0_SB_DQ<16>
  VSS54  = GND
  DQ17_B  = M_A_CPU0_SB_DQ<17>
  VSS55  = GND
  DQS2_B_T  = M_A_CPU0_SB_DQS_DP<2>
  DQS2_B_C  = M_A_CPU0_SB_DQS_DN<2>
  VSS56  = GND
  DQ20_B  = M_A_CPU0_SB_DQ<20>
  VSS57  = GND
  DQ21_B  = M_A_CPU0_SB_DQ<21>
  VSS58  = GND
  DQ24_B  = M_A_CPU0_SB_DQ<24>
  VSS59  = GND
  DQ25_B  = M_A_CPU0_SB_DQ<25>
  VSS60  = GND
  DQS3_B_T  = M_A_CPU0_SB_DQS_DP<3>
  DQS3_B_C  = M_A_CPU0_SB_DQS_DN<3>
  VSS61  = GND
  DQ28_B  = M_A_CPU0_SB_DQ<28>
  VSS62  = GND
  DQ29_B  = M_A_CPU0_SB_DQ<29>
  VSS63  = GND
  RFU1  = NC
  VIN_BULK1  = P12V_MEM_CPU0
  VIN_BULK2  = P12V_MEM_CPU0
  \pwr_good||fail_n\  = PWRGD_CHA_CPU0_DIMM0
  HAS  = PD_CHA_CPU0_DIMM0_SAA
  RFU2  = NC
  RFU3  = NC
  VSS64  = GND
  DQ2_A  = M_A_CPU0_SA_DQ<2>
  VSS65  = GND
  DQ3_A  = M_A_CPU0_SA_DQ<3>
  VSS66  = GND
  \dqs5_a_c||tdqs5_a_c||dqs5_a_t||tdqs5_a_t\  = M_A_CPU0_SA_DQS_DN<5>
  \dqs5_a_t||tdqs5_a_t\  = M_A_CPU0_SA_DQS_DP<5>
  VSS67  = GND
  DQ6_A  = M_A_CPU0_SA_DQ<6>
  VSS68  = GND
  DQ7_A  = M_A_CPU0_SA_DQ<7>
  VSS69  = GND
  DQ10_A  = M_A_CPU0_SA_DQ<10>
  VSS70  = GND
  DQ11_A  = M_A_CPU0_SA_DQ<11>
  VSS71  = GND
  \dqs6_a_c||tdqs6_a_c||dqs6_a_t||tdqs6_a_t\  = M_A_CPU0_SA_DQS_DN<6>
  \dqs6_a_t||tdqs6_a_t\  = M_A_CPU0_SA_DQS_DP<6>
  VSS72  = GND
  DQ14_A  = M_A_CPU0_SA_DQ<14>
  VSS73  = GND
  DQ15_A  = M_A_CPU0_SA_DQ<15>
  VSS74  = GND
  DQ18_A  = M_A_CPU0_SA_DQ<18>
  VSS75  = GND
  DQ19_A  = M_A_CPU0_SA_DQ<19>
  VSS76  = GND
  \dqs7_a_c||tdqs7_a_c\  = M_A_CPU0_SA_DQS_DN<7>
  \dqs7_a_t||tdqs7_a_t\  = M_A_CPU0_SA_DQS_DP<7>
  VSS77  = GND
  DQ22_A  = M_A_CPU0_SA_DQ<22>
  VSS78  = GND
  DQ23_A  = M_A_CPU0_SA_DQ<23>
  VSS79  = GND
  DQ26_A  = M_A_CPU0_SA_DQ<26>
  VSS80  = GND
  DQ27_A  = M_A_CPU0_SA_DQ<27>
  VSS81  = GND
  \dqs8_a_c||tdqs8_a_c\  = M_A_CPU0_SA_DQS_DN<8>
  \dqs8_a_t||tdqs8_a_t\  = M_A_CPU0_SA_DQS_DP<8>
  VSS82  = GND
  DQ30_A  = M_A_CPU0_SA_DQ<30>
  VSS83  = GND
  DQ31_A  = M_A_CPU0_SA_DQ<31>
  VSS84  = GND
  CB2_A  = M_A_CPU0_SA_CB<2>
  VSS85  = GND
  CB3_A  = M_A_CPU0_SA_CB<3>
  VSS86  = GND
  \dqs9_a_c||tdqs9_a_c\  = M_A_CPU0_SA_DQS_DN<9>
  \dqs9_a_t||tdqs9_a_t\  = M_A_CPU0_SA_DQS_DP<9>
  VSS87  = GND
  CB6_A  = M_A_CPU0_SA_CB<6>
  VSS88  = GND
  CB7_A  = M_A_CPU0_SA_CB<7>
  VSS89  = GND
  RESET_N  = M_A_CPU0_RESET_N
  VSS90  = GND
  CS1_A_N  = M_A_CPU0_SA_CS_N<1>
  VSS91  = GND
  CA1_A  = M_A_CPU0_SA_CA<1>
  VSS92  = GND
  CA3_A  = M_A_CPU0_SA_CA<3>
  VSS93  = GND
  CA5_A  = M_A_CPU0_SA_CA<5>
  VSS94  = GND
  CK_T  = M_A_CPU0_CLK_DP<0>
  CK_C  = M_A_CPU0_CLK_DN<0>
  VSS95  = GND
  RFU4  = NC
  CA1_B  = M_A_CPU0_SB_CA<1>
  VSS96  = GND
  CA3_B  = M_A_CPU0_SB_CA<3>
  VSS97  = GND
  CA5_B  = M_A_CPU0_SB_CA<5>
  VSS98  = GND
  PAR_B  = M_A_CPU0_SB_PAR
  VSS99  = GND
  CS1_B_N  = M_A_CPU0_SB_CS_N<1>
  VSS100  = GND
  RFU5  = NC
  RFU6  = NC
  VSS101  = GND
  CB6_B  = M_A_CPU0_SB_CB<6>
  VSS102  = GND
  CB7_B  = M_A_CPU0_SB_CB<7>
  VSS103  = GND
  DQS4_B_C  = M_A_CPU0_SB_DQS_DN<4>
  DQS4_B_T  = M_A_CPU0_SB_DQS_DP<4>
  VSS104  = GND
  CB2_B  = M_A_CPU0_SB_CB<2>
  VSS105  = GND
  CB3_B  = M_A_CPU0_SB_CB<3>
  VSS106  = GND
  DQ2_B  = M_A_CPU0_SB_DQ<2>
  VSS107  = GND
  DQ3_B  = M_A_CPU0_SB_DQ<3>
  VSS108  = GND
  \dqs5_b_c||tdqs5_b_c\  = M_A_CPU0_SB_DQS_DN<5>
  \dqs5_b_t||tdqs5_b_t\  = M_A_CPU0_SB_DQS_DP<5>
  VSS109  = GND
  DQ6_B  = M_A_CPU0_SB_DQ<6>
  VSS110  = GND
  DQ7_B  = M_A_CPU0_SB_DQ<7>
  VSS111  = GND
  DQ10_B  = M_A_CPU0_SB_DQ<10>
  VSS112  = GND
  DQ11_B  = M_A_CPU0_SB_DQ<11>
  VSS113  = GND
  \dqs6_b_c||tdqs6_b_c\  = M_A_CPU0_SB_DQS_DN<6>
  \dqs6_b_t||tdqs6_b_t\  = M_A_CPU0_SB_DQS_DP<6>
  VSS114  = GND
  DQ14_B  = M_A_CPU0_SB_DQ<14>
  VSS115  = GND
  DQ15_B  = M_A_CPU0_SB_DQ<15>
  VSS116  = GND
  DQ18_B  = M_A_CPU0_SB_DQ<18>
  VSS117  = GND
  DQ19_B  = M_A_CPU0_SB_DQ<19>
  VSS118  = GND
  \dqs7_b_c||tdqs7_b_c\  = M_A_CPU0_SB_DQS_DN<7>
  \dqs7_b_t||tdqs7_b_t\  = M_A_CPU0_SB_DQS_DP<7>
  VSS119  = GND
  DQ22_B  = M_A_CPU0_SB_DQ<22>
  VSS120  = GND
  DQ23_B  = M_A_CPU0_SB_DQ<23>
  VSS121  = GND
  DQ26_B  = M_A_CPU0_SB_DQ<26>
  VSS122  = GND
  DQ27_B  = M_A_CPU0_SB_DQ<27>
  VSS123  = GND
  \dqs8_b_c||tdqs8_b_c\  = M_A_CPU0_SB_DQS_DN<8>
  \dqs8_b_t||tdqs8_b_t\  = M_A_CPU0_SB_DQS_DP<8>
  VSS124  = GND
  DQ30_B  = M_A_CPU0_SB_DQ<30>
  VSS125  = GND
  DQ31_B  = M_A_CPU0_SB_DQ<31>
  VSS126  = GND
  G1  = GND
  G2  = GND
  G3  = GND

(kicad_pcb
	(version 20260206)
	(generator "pcbnew")
	(generator_version "10.0")
	(general
		(thickness 1.6)
		(legacy_teardrops no)
	)
	(paper "A4")
	(title_block
		(title "04192023_DAF0TMB3IC0_F0TG_MB_C_brd_V02_OCP.brd")
		(comment 1 "Grand Teton / footprint 2352 of 8354 (J1), pads 231-276 of 291")
	)
	(layers
		(0 "F.Cu" signal "TOP")
		(4 "In1.Cu" signal "GND")
		(6 "In2.Cu" signal "IN1")
		(8 "In3.Cu" signal "GND1")
		(10 "In4.Cu" signal "IN2")
		(12 "In5.Cu" signal "GND2")
		(14 "In6.Cu" signal "IN3")
		(16 "In7.Cu" signal "GND3")
		(18 "In8.Cu" signal "VCC")
		(20 "In9.Cu" signal "VCC1")
		(22 "In10.Cu" signal "GND4")
		(24 "In11.Cu" signal "IN4")
		(26 "In12.Cu" signal "GND5")
		(28 "In13.Cu" signal "IN5")
		(30 "In14.Cu" signal "GND6")
		(32 "In15.Cu" signal "IN6")
		(34 "In16.Cu" signal "GND7")
		(2 "B.Cu" signal "BOTTOM")
		(9 "F.Adhes" user "F.Adhesive")
		(11 "B.Adhes" user "B.Adhesive")
		(13 "F.Paste" user "Package Geometry/Pastemask Top")
		(15 "B.Paste" user "Package Geometry/Pastemask Bottom")
		(5 "F.SilkS" user "Ref Des/Silkscreen Top")
		(7 "B.SilkS" user "Ref Des/Silkscreen Bottom")
		(1 "F.Mask" user "Board Geometry/Soldermask Top")
		(3 "B.Mask" user "Board Geometry/Soldermask Bottom")
		(17 "Dwgs.User" user "User.Drawings")
		(19 "Cmts.User" user "User.Comments")
		(21 "Eco1.User" user "User.Eco1")
		(23 "Eco2.User" user "User.Eco2")
		(25 "Edge.Cuts" user "Board Geometry/Outline")
		(27 "Margin" user)
		(31 "F.CrtYd" user "Package Geometry/Place Bound Top")
		(29 "B.CrtYd" user "Package Geometry/Place Bound Bottom")
		(35 "F.Fab" user "Ref Des/Assembly Top")
		(33 "B.Fab" user "Ref Des/Assembly Bottom")
	)
	(footprint ""
		(layer "F.Cu")
		(at 305.31816 -255.560068 180)
		(property "Reference" "J1"
			(at -2.2098 -81.984088 0)
			(unlocked yes)
			(layer "F.SilkS")
			(effects
				(font
					(size 0.7874 0.5842)
					(thickness 0.1524)
				)
			)
		)
		(property "Value" ""
			(at 0 0 180)
			(layer "F.Fab")
			(effects
				(font
					(size 1.27 1.27)
				)
			)
		)
		(duplicate_pad_numbers_are_jumpers no)
		(pad "231" smd rect
			(at 2.050034 14.875002 90)
			(size 0.519938 1.4986)
			(layers "F.Cu" "F.Mask" "F.Paste")
			(net "Net_2254")
		)
		(pad "232" smd rect
			(at 2.050034 15.724886 90)
			(size 0.519938 1.4986)
			(layers "F.Cu" "F.Mask" "F.Paste")
			(net "Net_2255")
		)
		(pad "233" smd rect
			(at 2.050034 16.575024 90)
			(size 0.519938 1.4986)
			(layers "F.Cu" "F.Mask" "F.Paste")
			(net "GND")
		)
		(pad "234" smd rect
			(at 2.050034 17.424908 90)
			(size 0.519938 1.4986)
			(layers "F.Cu" "F.Mask" "F.Paste")
			(net "M_A_CPU0_SB_CB<6>")
		)
		(pad "235" smd rect
			(at 2.050034 18.275046 90)
			(size 0.519938 1.4986)
			(layers "F.Cu" "F.Mask" "F.Paste")
			(net "GND")
		)
		(pad "236" smd rect
			(at 2.050034 19.12493 90)
			(size 0.519938 1.4986)
			(layers "F.Cu" "F.Mask" "F.Paste")
			(net "M_A_CPU0_SB_CB<7>")
		)
		(pad "237" smd rect
			(at 2.050034 19.975068 90)
			(size 0.519938 1.4986)
			(layers "F.Cu" "F.Mask" "F.Paste")
			(net "GND")
		)
		(pad "238" smd rect
			(at 2.050034 20.824952 90)
			(size 0.519938 1.4986)
			(layers "F.Cu" "F.Mask" "F.Paste")
			(net "M_A_CPU0_SB_DQS_DN<4>")
		)
		(pad "239" smd rect
			(at 2.050034 21.67509 90)
			(size 0.519938 1.4986)
			(layers "F.Cu" "F.Mask" "F.Paste")
			(net "M_A_CPU0_SB_DQS_DP<4>")
		)
		(pad "240" smd rect
			(at 2.050034 22.524974 90)
			(size 0.519938 1.4986)
			(layers "F.Cu" "F.Mask" "F.Paste")
			(net "GND")
		)
		(pad "241" smd rect
			(at 2.050034 23.375112 90)
			(size 0.519938 1.4986)
			(layers "F.Cu" "F.Mask" "F.Paste")
			(net "M_A_CPU0_SB_CB<2>")
		)
		(pad "242" smd rect
			(at 2.050034 24.224996 90)
			(size 0.519938 1.4986)
			(layers "F.Cu" "F.Mask" "F.Paste")
			(net "GND")
		)
		(pad "243" smd rect
			(at 2.050034 25.07488 90)
			(size 0.519938 1.4986)
			(layers "F.Cu" "F.Mask" "F.Paste")
			(net "M_A_CPU0_SB_CB<3>")
		)
		(pad "244" smd rect
			(at 2.050034 25.925018 90)
			(size 0.519938 1.4986)
			(layers "F.Cu" "F.Mask" "F.Paste")
			(net "GND")
		)
		(pad "245" smd rect
			(at 2.050034 26.774902 90)
			(size 0.519938 1.4986)
			(layers "F.Cu" "F.Mask" "F.Paste")
			(net "M_A_CPU0_SB_DQ<2>")
		)
		(pad "246" smd rect
			(at 2.050034 27.62504 90)
			(size 0.519938 1.4986)
			(layers "F.Cu" "F.Mask" "F.Paste")
			(net "GND")
		)
		(pad "247" smd rect
			(at 2.050034 28.474924 90)
			(size 0.519938 1.4986)
			(layers "F.Cu" "F.Mask" "F.Paste")
			(net "M_A_CPU0_SB_DQ<3>")
		)
		(pad "248" smd rect
			(at 2.050034 29.325062 90)
			(size 0.519938 1.4986)
			(layers "F.Cu" "F.Mask" "F.Paste")
			(net "GND")
		)
		(pad "249" smd rect
			(at 2.050034 30.174946 90)
			(size 0.519938 1.4986)
			(layers "F.Cu" "F.Mask" "F.Paste")
			(net "M_A_CPU0_SB_DQS_DN<5>")
		)
		(pad "250" smd rect
			(at 2.050034 31.025084 90)
			(size 0.519938 1.4986)
			(layers "F.Cu" "F.Mask" "F.Paste")
			(net "M_A_CPU0_SB_DQS_DP<5>")
		)
		(pad "251" smd rect
			(at 2.050034 31.874968 90)
			(size 0.519938 1.4986)
			(layers "F.Cu" "F.Mask" "F.Paste")
			(net "GND")
		)
		(pad "252" smd rect
			(at 2.050034 32.725106 90)
			(size 0.519938 1.4986)
			(layers "F.Cu" "F.Mask" "F.Paste")
			(net "M_A_CPU0_SB_DQ<6>")
		)
		(pad "253" smd rect
			(at 2.050034 33.57499 90)
			(size 0.519938 1.4986)
			(layers "F.Cu" "F.Mask" "F.Paste")
			(net "GND")
		)
		(pad "254" smd rect
			(at 2.050034 34.425128 90)
			(size 0.519938 1.4986)
			(layers "F.Cu" "F.Mask" "F.Paste")
			(net "M_A_CPU0_SB_DQ<7>")
		)
		(pad "255" smd rect
			(at 2.050034 35.275012 90)
			(size 0.519938 1.4986)
			(layers "F.Cu" "F.Mask" "F.Paste")
			(net "GND")
		)
		(pad "256" smd rect
			(at 2.050034 36.124896 90)
			(size 0.519938 1.4986)
			(layers "F.Cu" "F.Mask" "F.Paste")
			(net "M_A_CPU0_SB_DQ<10>")
		)
		(pad "257" smd rect
			(at 2.050034 36.975034 90)
			(size 0.519938 1.4986)
			(layers "F.Cu" "F.Mask" "F.Paste")
			(net "GND")
		)
		(pad "258" smd rect
			(at 2.050034 37.824918 90)
			(size 0.519938 1.4986)
			(layers "F.Cu" "F.Mask" "F.Paste")
			(net "M_A_CPU0_SB_DQ<11>")
		)
		(pad "259" smd rect
			(at 2.050034 38.675056 90)
			(size 0.519938 1.4986)
			(layers "F.Cu" "F.Mask" "F.Paste")
			(net "GND")
		)
		(pad "260" smd rect
			(at 2.050034 39.52494 90)
			(size 0.519938 1.4986)
			(layers "F.Cu" "F.Mask" "F.Paste")
			(net "M_A_CPU0_SB_DQS_DN<6>")
		)
		(pad "261" smd rect
			(at 2.050034 40.375078 90)
			(size 0.519938 1.4986)
			(layers "F.Cu" "F.Mask" "F.Paste")
			(net "M_A_CPU0_SB_DQS_DP<6>")
		)
		(pad "262" smd rect
			(at 2.050034 41.224962 90)
			(size 0.519938 1.4986)
			(layers "F.Cu" "F.Mask" "F.Paste")
			(net "GND")
		)
		(pad "263" smd rect
			(at 2.050034 42.0751 90)
			(size 0.519938 1.4986)
			(layers "F.Cu" "F.Mask" "F.Paste")
			(net "M_A_CPU0_SB_DQ<14>")
		)
		(pad "264" smd rect
			(at 2.050034 42.924984 90)
			(size 0.519938 1.4986)
			(layers "F.Cu" "F.Mask" "F.Paste")
			(net "GND")
		)
		(pad "265" smd rect
			(at 2.050034 43.775122 90)
			(size 0.519938 1.4986)
			(layers "F.Cu" "F.Mask" "F.Paste")
			(net "M_A_CPU0_SB_DQ<15>")
		)
		(pad "266" smd rect
			(at 2.050034 44.625006 90)
			(size 0.519938 1.4986)
			(layers "F.Cu" "F.Mask" "F.Paste")
			(net "GND")
		)
		(pad "267" smd rect
			(at 2.050034 45.47489 90)
			(size 0.519938 1.4986)
			(layers "F.Cu" "F.Mask" "F.Paste")
			(net "M_A_CPU0_SB_DQ<18>")
		)
		(pad "268" smd rect
			(at 2.050034 46.325028 90)
			(size 0.519938 1.4986)
			(layers "F.Cu" "F.Mask" "F.Paste")
			(net "GND")
		)
		(pad "269" smd rect
			(at 2.050034 47.174912 90)
			(size 0.519938 1.4986)
			(layers "F.Cu" "F.Mask" "F.Paste")
			(net "M_A_CPU0_SB_DQ<19>")
		)
		(pad "270" smd rect
			(at 2.050034 48.02505 90)
			(size 0.519938 1.4986)
			(layers "F.Cu" "F.Mask" "F.Paste")
			(net "GND")
		)
		(pad "271" smd rect
			(at 2.050034 48.874934 90)
			(size 0.519938 1.4986)
			(layers "F.Cu" "F.Mask" "F.Paste")
			(net "M_A_CPU0_SB_DQS_DN<7>")
		)
		(pad "272" smd rect
			(at 2.050034 49.725072 90)
			(size 0.519938 1.4986)
			(layers "F.Cu" "F.Mask" "F.Paste")
			(net "M_A_CPU0_SB_DQS_DP<7>")
		)
		(pad "273" smd rect
			(at 2.050034 50.574956 90)
			(size 0.519938 1.4986)
			(layers "F.Cu" "F.Mask" "F.Paste")
			(net "GND")
		)
		(pad "274" smd rect
			(at 2.050034 51.425094 90)
			(size 0.519938 1.4986)
			(layers "F.Cu" "F.Mask" "F.Paste")
			(net "M_A_CPU0_SB_DQ<22>")
		)
		(pad "275" smd rect
			(at 2.050034 52.274978 90)
			(size 0.519938 1.4986)
			(layers "F.Cu" "F.Mask" "F.Paste")
			(net "GND")
		)
		(pad "276" smd rect
			(at 2.050034 53.125116 90)
			(size 0.519938 1.4986)
			(layers "F.Cu" "F.Mask" "F.Paste")
			(net "M_A_CPU0_SB_DQ<23>")
		)
	)
)
